# TIMECARD (Time Appliance Project (Time Card)) — schematic netlist excerpt (pin names and nets, part order shuffled) for the footprints in the layout excerpt that follows; sources: Cadence DE-HDL packaged netlist, KiCad conversion of R4006-B0001-02_R01.brd

C291  CAPACITOR  22UF 10V 20%  pkg SMC_0805R_H057  page 14 : \1\ = XP2R5V_FPGA ; \2\ = SG
DS8  OPTICAL  pkg SMC_DS_063X031_V4  page 26 : A = UNNAMED_14_OPTICAL_I142_A ; C = SG

(kicad_pcb
	(version 20260206)
	(generator "pcbnew")
	(generator_version "10.0")
	(general
		(thickness 1.6)
		(legacy_teardrops no)
	)
	(paper "A4")
	(title_block
		(title "timecard-production-celestica-r4006 — R4006-B0001-02_R01.brd")
		(comment 1 "Time Appliance Project (Time Card) / footprints 218-219 of 1113")
	)
	(layers
		(0 "F.Cu" signal "TOP")
		(4 "In1.Cu" signal "L02_GND1")
		(6 "In2.Cu" signal "L03_SIG1")
		(8 "In3.Cu" signal "L04_GND2")
		(10 "In4.Cu" signal "L05_VCC1")
		(12 "In5.Cu" signal "L06_VCC2")
		(14 "In6.Cu" signal "L07_GND3")
		(16 "In7.Cu" signal "L08_SIG2")
		(18 "In8.Cu" signal "L09_GND4")
		(2 "B.Cu" signal "BOTTOM")
		(9 "F.Adhes" user "F.Adhesive")
		(11 "B.Adhes" user "B.Adhesive")
		(13 "F.Paste" user "Package Geometry/Pastemask Top")
		(15 "B.Paste" user "Package Geometry/Pastemask Bottom")
		(5 "F.SilkS" user "Ref Des/Silkscreen Top")
		(7 "B.SilkS" user "Ref Des/Silkscreen Bottom")
		(1 "F.Mask" user "Board Geometry/Soldermask Top")
		(3 "B.Mask" user "Board Geometry/Soldermask Bottom")
		(17 "Dwgs.User" user "User.Drawings")
		(19 "Cmts.User" user "User.Comments")
		(21 "Eco1.User" user "User.Eco1")
		(23 "Eco2.User" user "User.Eco2")
		(25 "Edge.Cuts" user "Board Geometry/Outline")
		(27 "Margin" user)
		(31 "F.CrtYd" user "Package Geometry/Place Bound Top")
		(29 "B.CrtYd" user "Package Geometry/Place Bound Bottom")
		(35 "F.Fab" user "Ref Des/Assembly Top")
		(33 "B.Fab" user "Ref Des/Assembly Bottom")
	)
	(footprint ""
		(layer "F.Cu")
		(at 95.631 -26.924)
		(property "Reference" "C291"
			(at -1.397 -1.73863 0)
			(unlocked yes)
			(layer "F.SilkS")
			(effects
				(font
					(size 0.7874 0.5842)
					(thickness 0.1524)
				)
			)
		)
		(property "Value" "VAL*"
			(at 0.0762 3.134106 0)
			(unlocked yes)
			(layer "F.Fab")
			(hide yes)
			(effects
				(font
					(size 0.7874 0.5842)
					(thickness 0.1524)
				)
			)
		)
		(property "Device Type" "CAPACITOR-G107-0F226-CM,22UF,2A"
			(at 0.0508 2.194306 0)
			(unlocked yes)
			(layer "F.Fab")
			(hide yes)
			(effects
				(font
					(size 0.7874 0.5842)
					(thickness 0.1524)
				)
			)
		)
		(property "User Part Number" "PARTNUM*"
			(at 0.1016 5.013706 0)
			(unlocked yes)
			(layer "Cmts.User")
			(hide yes)
			(effects
				(font
					(size 0.7874 0.5842)
					(thickness 0.1524)
				)
			)
		)
		(property "Tolerance" "TOL*"
			(at 0.0762 4.048506 0)
			(unlocked yes)
			(layer "Cmts.User")
			(hide yes)
			(effects
				(font
					(size 0.7874 0.5842)
					(thickness 0.1524)
				)
			)
		)
		(duplicate_pad_numbers_are_jumpers no)
		(fp_line
			(start -1.5748 -0.9398)
			(end -1.5748 0.9398)
			(stroke
				(width 0.1)
				(type default)
			)
			(layer "F.SilkS")
		)
		(fp_line
			(start -1.5748 0.9398)
			(end 1.5748 0.9398)
			(stroke
				(width 0.1)
				(type default)
			)
			(layer "F.SilkS")
		)
		(fp_line
			(start 1.5748 -0.9398)
			(end -1.5748 -0.9398)
			(stroke
				(width 0.1)
				(type default)
			)
			(layer "F.SilkS")
		)
		(fp_line
			(start 1.5748 0.9398)
			(end 1.5748 -0.9398)
			(stroke
				(width 0.1)
				(type default)
			)
			(layer "F.SilkS")
		)
		(fp_rect
			(start 1.5748 -0.9398)
			(end -1.5748 0.9398)
			(stroke
				(width 0)
				(type default)
			)
			(fill no)
			(layer "F.CrtYd")
		)
		(fp_line
			(start -1.016 -0.635)
			(end -1.016 0.635)
			(stroke
				(width 0.1)
				(type default)
			)
			(layer "F.Fab")
		)
		(fp_line
			(start -1.016 0.635)
			(end 1.016 0.635)
			(stroke
				(width 0.1)
				(type default)
			)
			(layer "F.Fab")
		)
		(fp_line
			(start 1.016 -0.635)
			(end -1.016 -0.635)
			(stroke
				(width 0.1)
				(type default)
			)
			(layer "F.Fab")
		)
		(fp_line
			(start 1.016 0.635)
			(end 1.016 -0.635)
			(stroke
				(width 0.1)
				(type default)
			)
			(layer "F.Fab")
		)
		(pad "1" smd rect
			(at -0.8382 0)
			(size 0.9652 1.3716)
			(layers "F.Cu" "F.Mask" "F.Paste")
			(net "XP2R5V_FPGA")
		)
		(pad "2" smd rect
			(at 0.8382 0)
			(size 0.9652 1.3716)
			(layers "F.Cu" "F.Mask" "F.Paste")
			(net "SG")
		)
		(zone
			(layer "F.Cu")
			(hatch none 0.5)
			(connect_pads
				(clearance 0)
			)
			(min_thickness 0.25)
			(keepout
				(tracks not_allowed)
				(vias allowed)
				(pads allowed)
				(copperpour not_allowed)
				(footprints allowed)
			)
			(placement
				(enabled no)
				(sheetname "")
			)
			(fill
				(thermal_gap 0.5)
				(thermal_bridge_width 0.5)
				(island_removal_mode 0)
			)
			(polygon
				(pts
					(xy 95.8596 -27.559) (xy 95.4024 -27.559) (xy 95.4024 -26.289) (xy 95.8596 -26.289)
				)
			)
		)
		(zone
			(layer "F.Cu")
			(hatch none 0.5)
			(connect_pads
				(clearance 0)
			)
			(min_thickness 0.25)
			(keepout
				(tracks allowed)
				(vias not_allowed)
				(pads allowed)
				(copperpour not_allowed)
				(footprints allowed)
			)
			(placement
				(enabled no)
				(sheetname "")
			)
			(fill
				(thermal_gap 0.5)
				(thermal_bridge_width 0.5)
				(island_removal_mode 0)
			)
			(polygon
				(pts
					(xy 95.8596 -27.559) (xy 95.4024 -27.559) (xy 95.4024 -26.289) (xy 95.8596 -26.289)
				)
			)
		)
	)
	(footprint ""
		(layer "F.Cu")
		(at 144.050004 -104.350058 -90)
		(property "Reference" "DS8"
			(at 0.718058 1.397254 90)
			(unlocked yes)
			(layer "F.SilkS")
			(effects
				(font
					(size 0.635 0.4064)
					(thickness 0.1524)
				)
			)
		)
		(property "Value" ""
			(at 0 0 270)
			(layer "F.Fab")
			(effects
				(font
					(size 1.27 1.27)
				)
			)
		)
		(property "Device Type" "OPTICAL-G170-10143-01"
			(at 0.1778 1.483081 270)
			(unlocked yes)
			(layer "F.Fab")
			(hide yes)
			(effects
				(font
					(size 0.786892 0.583946)
					(thickness 0.000001)
				)
			)
		)
		(property "User Part Number" "PARTNUM*"
			(at 0.1778 2.422881 270)
			(unlocked yes)
			(layer "Cmts.User")
			(hide yes)
			(effects
				(font
					(size 0.786892 0.583946)
					(thickness 0.000001)
				)
			)
		)
		(duplicate_pad_numbers_are_jumpers no)
		(fp_line
			(start -1.0668 1.3462)
			(end -2.3368 1.3462)
			(stroke
				(width 0.1)
				(type default)
			)
			(layer "F.SilkS")
		)
		(fp_line
			(start -1.7018 0.7112)
			(end -1.7018 1.9812)
			(stroke
				(width 0.1)
				(type default)
			)
			(layer "F.SilkS")
		)
		(fp_line
			(start -1.397508 0.704088)
			(end -1.397508 -0.704088)
			(stroke
				(width 0.1)
				(type default)
			)
			(layer "F.SilkS")
		)
		(fp_line
			(start 1.397508 0.704088)
			(end -1.397508 0.704088)
			(stroke
				(width 0.1)
				(type default)
			)
			(layer "F.SilkS")
		)
		(fp_line
			(start -1.397508 -0.704088)
			(end 1.397508 -0.704088)
			(stroke
				(width 0.1)
				(type default)
			)
			(layer "F.SilkS")
		)
		(fp_line
			(start 1.397508 -0.704088)
			(end 1.397508 0.704088)
			(stroke
				(width 0.1)
				(type default)
			)
			(layer "F.SilkS")
		)
		(fp_rect
			(start 1.905508 0.704088)
			(end 1.397508 -0.704088)
			(stroke
				(width 0)
				(type default)
			)
			(fill yes)
			(layer "F.SilkS")
		)
		(fp_rect
			(start 1.905508 0.958088)
			(end -1.651508 -0.958088)
			(stroke
				(width 0)
				(type default)
			)
			(fill no)
			(layer "F.CrtYd")
		)
		(fp_line
			(start -0.6858 1.0922)
			(end -1.9558 1.0922)
			(stroke
				(width 0.1)
				(type default)
			)
			(layer "F.Fab")
		)
		(fp_line
			(start -1.3208 0.4572)
			(end -1.3208 1.7272)
			(stroke
				(width 0.1)
				(type default)
			)
			(layer "F.Fab")
		)
		(fp_line
			(start -0.850138 0.450088)
			(end 0.850138 0.450088)
			(stroke
				(width 0.1)
				(type default)
			)
			(layer "F.Fab")
		)
		(fp_line
			(start 0.850138 0.450088)
			(end 0.850138 -0.450088)
			(stroke
				(width 0.1)
				(type default)
			)
			(layer "F.Fab")
		)
		(fp_line
			(start -0.850138 -0.450088)
			(end -0.850138 0.450088)
			(stroke
				(width 0.1)
				(type default)
			)
			(layer "F.Fab")
		)
		(fp_line
			(start 0.850138 -0.450088)
			(end -0.850138 -0.450088)
			(stroke
				(width 0.1)
				(type default)
			)
			(layer "F.Fab")
		)
		(fp_rect
			(start 0.850138 0.450088)
			(end 0.342138 -0.450088)
			(stroke
				(width 0)
				(type default)
			)
			(fill yes)
			(layer "F.Fab")
		)
		(fp_text user "A"
			(at -1.155192 1.683004 0)
			(unlocked yes)
			(layer "F.SilkS")
			(effects
				(font
					(size 0.635 0.4064)
					(thickness 0.1524)
				)
			)
		)
		(fp_text user "C"
			(at 2.400808 -0.983996 0)
			(unlocked yes)
			(layer "F.SilkS")
			(effects
				(font
					(size 0.635 0.4064)
					(thickness 0.1524)
				)
			)
		)
		(fp_text user "A"
			(at -1.49733 -0.7112 0)
			(unlocked yes)
			(layer "F.Fab")
			(effects
				(font
					(size 0.7874 0.5842)
					(thickness 0.1524)
				)
			)
		)
		(fp_text user "C"
			(at 1.773428 -0.856996 0)
			(unlocked yes)
			(layer "F.Fab")
			(effects
				(font
					(size 0.7874 0.5842)
					(thickness 0.1524)
				)
			)
		)
		(pad "A" smd rect
			(at -0.749808 0 270)
			(size 0.7874 0.7874)
			(layers "F.Cu" "F.Mask" "F.Paste")
			(net "UNNAMED_14_OPTICAL_I142_A")
		)
		(pad "C" smd rect
			(at 0.749808 0 270)
			(size 0.7874 0.7874)
			(layers "F.Cu" "F.Mask" "F.Paste")
			(net "SG")
		)
	)
)
